(kicad_pcb
	(version 20221018)
	(generator pcbnew)
	(general
    (thickness 1.6)
  )
	(paper "A4")
	(title_block
    (title "NUC Computer Cluster Power Breakout HW")
    (date "2023-10-18")
    (rev "1.4.3")
    (company "Antmicro Ltd.")
		(comment 9 "footprints 215-219 of 234")
	)
	(layers
    (0 "F.Cu" mixed)
    (1 "In1.Cu" power)
    (2 "In2.Cu" mixed)
    (31 "B.Cu" power)
    (32 "B.Adhes" user "B.Adhesive")
    (33 "F.Adhes" user "F.Adhesive")
    (34 "B.Paste" user)
    (35 "F.Paste" user)
    (36 "B.SilkS" user "B.Silkscreen")
    (37 "F.SilkS" user "F.Silkscreen")
    (38 "B.Mask" user)
    (39 "F.Mask" user)
    (40 "Dwgs.User" user "User.Drawings")
    (41 "Cmts.User" user "User.Comments")
    (42 "Eco1.User" user "User.Eco1")
    (43 "Eco2.User" user "User.Eco2")
    (44 "Edge.Cuts" user)
    (45 "Margin" user)
    (46 "B.CrtYd" user "B.Courtyard")
    (47 "F.CrtYd" user "F.Courtyard")
    (48 "B.Fab" user)
    (49 "F.Fab" user)
  )
	(footprint "antmicro-footprints:D_SOD-323" (layer "F.Cu")
    (at 182.1 91.35 -90)
    (property "Author" "Antmicro")
    (property "License" "Apache-2.0")
    (property "MPN" "BZT52B15SV-T")
    (property "Manufacturer" "Rectron")
    (property "Sheetfile" "power-switch.kicad_sch")
    (property "Sheetname" "Power switch 5")
    (property "ki_description" "Zener Single Diode, AEC-Q101, 15 V, 500 mW, SOD-323, 2 Pins, 150 °C, Surface Mount")
    (property "ki_keywords" "SMT, DIODE, SEMICONDUCTOR, ZENER")
    (attr smd)
    (fp_text reference "D19" (at -0.85 -1.15) (layer "F.SilkS")
        (effects (font (size 0.7 0.7) (thickness 0.15)) (justify left bottom))
    )
    (fp_text value "BZT52B15SV-T" (at 0 1.841 -90) (layer "F.Fab")
        (effects (font (size 0.7 0.7) (thickness 0.15)) (justify left bottom))
    )
    (fp_text user "License: Apache-2.0" (at -1.4 3.841 -90) (layer "F.Fab") hide
        (effects (font (size 0.7 0.7) (thickness 0.15)) (justify left bottom))
    )
    (fp_text user "${REFERENCE}" (at -1.4 5.041 -90) (layer "F.Fab") hide
        (effects (font (size 0.7 0.7) (thickness 0.15)) (justify left bottom))
    )
    (fp_text user "Author: Antmicro" (at -1.4 6.241 -90) (layer "F.Fab") hide
        (effects (font (size 0.7 0.7) (thickness 0.15)) (justify left bottom))
    )
    (fp_line (start -0.949 -0.749) (end -0.949 -0.499)
      (stroke (width 0.15) (type solid)) (layer "F.SilkS"))
    (fp_line (start -0.949 0.501) (end -0.949 0.751)
      (stroke (width 0.15) (type solid)) (layer "F.SilkS"))
    (fp_line (start -0.6 -0.499) (end -0.6 0.499)
      (stroke (width 0.15) (type solid)) (layer "F.SilkS"))
    (fp_line (start -0.577 -0.749) (end -0.949 -0.749)
      (stroke (width 0.15) (type solid)) (layer "F.SilkS"))
    (fp_line (start -0.577 0.751) (end -0.949 0.751)
      (stroke (width 0.15) (type solid)) (layer "F.SilkS"))
    (fp_line (start 0.625 -0.736) (end 0.949 -0.736)
      (stroke (width 0.15) (type solid)) (layer "F.SilkS"))
    (fp_line (start 0.949 -0.736) (end 0.949 -0.499)
      (stroke (width 0.15) (type solid)) (layer "F.SilkS"))
    (fp_line (start 0.95 0.501) (end 0.95 0.751)
      (stroke (width 0.15) (type solid)) (layer "F.SilkS"))
    (fp_line (start 0.95 0.751) (end 0.649 0.751)
      (stroke (width 0.15) (type solid)) (layer "F.SilkS"))
    (fp_rect (start -1.6 -0.925) (end 1.6 0.925)
      (stroke (width 0.05) (type solid)) (fill none) (layer "F.CrtYd"))
    (fp_line (start -0.902 0.699) (end -0.902 -0.699)
      (stroke (width 0.15) (type solid)) (layer "F.Fab"))
    (fp_line (start -0.902 0.699) (end 0.9 0.699)
      (stroke (width 0.15) (type solid)) (layer "F.Fab"))
    (fp_line (start 0.9 -0.699) (end -0.902 -0.699)
      (stroke (width 0.15) (type solid)) (layer "F.Fab"))
    (fp_line (start 0.9 -0.699) (end 0.9 0.699)
      (stroke (width 0.15) (type solid)) (layer "F.Fab"))
    (pad "1" smd rect (at -1.125 0.001 270) (size 0.8 0.8) (layers "F.Cu" "F.Paste" "F.Mask")
      (net 11 "VCC12V0") (pinfunction "C") (pintype "passive"))
    (pad "2" smd rect (at 1.124 0.001 270) (size 0.8 0.8) (layers "F.Cu" "F.Paste" "F.Mask")
      (net 87 "Net-(D19-A)") (pinfunction "A") (pintype "passive"))
  )
	(footprint "antmicro-footprints:USB-C_Receptacle_GCT_USB4145-03-0070-C" (layer "F.Cu")
    (at 186.99 113.55 90)
    (property "Author" "Antmicro")
    (property "License" "Apache-2.0")
    (property "MPN" "USB4145-03-0070-C")
    (property "Manufacturer" "GCT")
    (property "Sheetfile" "ftdi-module.kicad_sch")
    (property "Sheetname" "FTDI")
    (property "ki_description" "USB-C (USB TYPE-C) USB 2.0 Receptacle Connector 24 (16+8 Dummy) Postion  Surface Mount, Vertical")
    (property "ki_keywords" "USB, CONNECTOR, SMT, VERTICAL")
    (attr smd)
    (fp_text reference "U1" (at 0.85 0.81 90) (layer "F.SilkS")
        (effects (font (size 0.7 0.7) (thickness 0.15)) (justify left bottom))
    )
    (fp_text value "USB-C_GCT_USB4145-03-0070-C" (at 11.365 3.465 90) (layer "F.Fab")
        (effects (font (size 0.7 0.7) (thickness 0.15)) (justify left bottom))
    )
    (fp_text user "${REFERENCE}" (at -4.72 6.665 90) (layer "F.Fab") hide
        (effects (font (size 0.7 0.7) (thickness 0.15)) (justify left bottom))
    )
    (fp_text user "Author: Antmicro" (at -4.72 7.865 90) (layer "F.Fab") hide
        (effects (font (size 0.7 0.7) (thickness 0.15)) (justify left bottom))
    )
    (fp_text user "License: Apache-2.0" (at -4.72 5.465 90) (layer "F.Fab") hide
        (effects (font (size 0.7 0.7) (thickness 0.15)) (justify left bottom))
    )
    (fp_line (start -2.28 -1.47) (end -1.72 -1.47)
      (stroke (width 0.15) (type solid)) (layer "F.SilkS"))
    (fp_line (start -2.28 1.69) (end -1.72 1.69)
      (stroke (width 0.15) (type solid)) (layer "F.SilkS"))
    (fp_line (start 1.72 -1.47) (end 2.28 -1.47)
      (stroke (width 0.15) (type solid)) (layer "F.SilkS"))
    (fp_line (start 1.72 1.69) (end 2.28 1.69)
      (stroke (width 0.15) (type solid)) (layer "F.SilkS"))
    (fp_circle (center -2.75 -2.39) (end -2.7 -2.39)
      (stroke (width 0.15) (type solid)) (fill solid) (layer "F.SilkS"))
    (fp_rect (start -4.9 -2.1) (end 4.9 2.1)
      (stroke (width 0.05) (type solid)) (fill none) (layer "F.CrtYd"))
    (fp_rect (start -4.5 -1.9) (end 4.5 1.9)
      (stroke (width 0.15) (type solid)) (fill none) (layer "F.Fab"))
    (pad "" np_thru_hole circle (at -4 0.11 90) (size 0.66 0.66) (drill 0.66) (layers "*.Cu" "*.Mask"))
    (pad "" np_thru_hole circle (at 4 0.11 90) (size 0.66 0.66) (drill 0.66) (layers "*.Cu" "*.Mask"))
    (pad "A1" smd rect (at -2.75 -1.375 90) (size 0.3 1.15) (layers "F.Cu" "F.Paste" "F.Mask")
      (net 77 "GNDD") (pinfunction "GND") (pintype "power_in"))
    (pad "A4" smd rect (at -1.25 -1.375 90) (size 0.3 1.15) (layers "F.Cu" "F.Paste" "F.Mask")
      (net 10 "VBUS") (pinfunction "VBUS") (pintype "passive"))
    (pad "A5" smd rect (at -0.75 -1.375 90) (size 0.3 1.15) (layers "F.Cu" "F.Paste" "F.Mask")
      (net 113 "Net-(U1-CC_{1})") (pinfunction "CC_{1}") (pintype "bidirectional"))
    (pad "A6" smd rect (at -0.25 -1.375 90) (size 0.3 1.15) (layers "F.Cu" "F.Paste" "F.Mask")
      (net 14 "/FTDI/USB_D+") (pinfunction "D_{A}+") (pintype "bidirectional"))
    (pad "A7" smd rect (at 0.25 -1.375 90) (size 0.3 1.15) (layers "F.Cu" "F.Paste" "F.Mask")
      (net 15 "/FTDI/USB_D-") (pinfunction "D_{A}-") (pintype "bidirectional"))
    (pad "A8" smd rect (at 0.75 -1.375 90) (size 0.3 1.15) (layers "F.Cu" "F.Paste" "F.Mask")
      (net 117 "Net-(U1-SBU_{1})") (pinfunction "SBU_{1}") (pintype "bidirectional"))
    (pad "A9" smd rect (at 1.25 -1.375 90) (size 0.3 1.15) (layers "F.Cu" "F.Paste" "F.Mask")
      (net 10 "VBUS") (pinfunction "VBUS") (pintype "passive"))
    (pad "A12" smd rect (at 2.75 -1.375 90) (size 0.3 1.15) (layers "F.Cu" "F.Paste" "F.Mask")
      (net 77 "GNDD") (pinfunction "GND") (pintype "passive"))
    (pad "B1" smd rect (at 2.75 1.595 90) (size 0.3 1.15) (layers "F.Cu" "F.Paste" "F.Mask")
      (net 77 "GNDD") (pinfunction "GND") (pintype "passive"))
    (pad "B4" smd rect (at 1.25 1.595 90) (size 0.3 1.15) (layers "F.Cu" "F.Paste" "F.Mask")
      (net 10 "VBUS") (pinfunction "VBUS") (pintype "passive"))
    (pad "B5" smd rect (at 0.75 1.595 90) (size 0.3 1.15) (layers "F.Cu" "F.Paste" "F.Mask")
      (net 114 "Net-(U1-CC_{2})") (pinfunction "CC_{2}") (pintype "bidirectional"))
    (pad "B6" smd rect (at 0.25 1.595 90) (size 0.3 1.15) (layers "F.Cu" "F.Paste" "F.Mask")
      (net 14 "/FTDI/USB_D+") (pinfunction "D_{B}+") (pintype "bidirectional"))
    (pad "B7" smd rect (at -0.25 1.595 90) (size 0.3 1.15) (layers "F.Cu" "F.Paste" "F.Mask")
      (net 15 "/FTDI/USB_D-") (pinfunction "D_{B}-") (pintype "bidirectional"))
    (pad "B8" smd rect (at -0.75 1.595 90) (size 0.3 1.15) (layers "F.Cu" "F.Paste" "F.Mask")
      (net 118 "Net-(U1-SBU_{2})") (pinfunction "SBU_{2}") (pintype "bidirectional"))
    (pad "B9" smd rect (at -1.25 1.595 90) (size 0.3 1.15) (layers "F.Cu" "F.Paste" "F.Mask")
      (net 10 "VBUS") (pinfunction "VBUS") (pintype "passive"))
    (pad "B12" smd rect (at -2.75 1.595 90) (size 0.3 1.15) (layers "F.Cu" "F.Paste" "F.Mask")
      (net 77 "GNDD") (pinfunction "GND") (pintype "passive"))
    (pad "SH" thru_hole oval (at -4 -1.32 90) (size 1.6 1.1) (drill oval 1.1 0.6) (layers "*.Cu" "*.Mask")
      (net 136 "Net-(FB3-Pad1)") (pinfunction "SH") (pintype "passive"))
    (pad "SH" thru_hole oval (at -4 1.54 90) (size 1.6 1.1) (drill oval 1.1 0.6) (layers "*.Cu" "*.Mask")
      (net 136 "Net-(FB3-Pad1)") (pinfunction "SH") (pintype "passive"))
    (pad "SH" thru_hole oval (at 4 -1.32 90) (size 1.6 1.1) (drill oval 1.1 0.6) (layers "*.Cu" "*.Mask")
      (net 136 "Net-(FB3-Pad1)") (pinfunction "SH") (pintype "passive"))
    (pad "SH" thru_hole oval (at 4 1.54 90) (size 1.6 1.1) (drill oval 1.1 0.6) (layers "*.Cu" "*.Mask")
      (net 136 "Net-(FB3-Pad1)") (pinfunction "SH") (pintype "passive"))
  )
	(footprint "antmicro-footprints:R_0402_1005Metric" (layer "F.Cu")
    (at 169.8 109.975 180)
    (descr "Resistor SMD 0402")
    (tags "resistor SMD 0402")
    (property "Author" "Antmicro")
    (property "License" "Apache-2.0")
    (property "MPN" "CR0402-FX-2200GLF")
    (property "Manufacturer" "Bourns")
    (property "Sheetfile" "ftdi-module.kicad_sch")
    (property "Sheetname" "FTDI")
    (property "Tolerance" "1%")
    (property "Val" "220R")
    (property "ki_description" "SMD Chip Resistor, 220 ohm, ± 1%, 62.5 mW, 0402 [1005 Metric], Thick Film, General Purpose")
    (property "ki_keywords" "0402, SMT, RESISTOR, PASSIVE")
    (attr smd)
    (fp_text reference "R74" (at -1.2 -1.35) (layer "F.SilkS")
        (effects (font (size 0.7 0.7) (thickness 0.15)) (justify right bottom))
    )
    (fp_text value "R_220R_0402" (at -1.011843 1.772047) (layer "F.Fab")
        (effects (font (size 0.7 0.7) (thickness 0.15)) (justify right bottom))
    )
    (fp_text user "License: Apache-2.0" (at -0.95 5.169) (layer "F.Fab") hide
        (effects (font (size 0.7 0.7) (thickness 0.15)) (justify right bottom))
    )
    (fp_text user "Author: Antmicro" (at -0.95 4.169) (layer "F.Fab") hide
        (effects (font (size 0.7 0.7) (thickness 0.15)) (justify right bottom))
    )
    (fp_text user "${REFERENCE}" (at -0.95 3.168) (layer "F.Fab") hide
        (effects (font (size 0.7 0.7) (thickness 0.15)) (justify right bottom))
    )
    (fp_rect (start -0.925 -0.47) (end 0.925 0.47)
      (stroke (width 0.05) (type default)) (fill none) (layer "F.CrtYd"))
    (fp_rect (start -0.5 -0.25) (end 0.5 0.25)
      (stroke (width 0.15) (type solid)) (fill none) (layer "F.Fab"))
    (pad "1" smd roundrect (at -0.48 0 180) (size 0.59 0.64) (layers "F.Cu" "F.Paste" "F.Mask") (roundrect_rratio 0.25)
      (net 77 "GNDD") (pintype "passive"))
    (pad "2" smd roundrect (at 0.48 0 180) (size 0.59 0.64) (layers "F.Cu" "F.Paste" "F.Mask") (roundrect_rratio 0.25)
      (net 147 "Net-(R74-Pad2)") (pintype "passive"))
  )
	(footprint "antmicro-footprints:LED_0603_1608Metric_G" (layer "F.Cu")
    (at 128.4 53.85)
    (descr "LED SMD 0603 Green")
    (tags "LED SMD 0603 Green")
    (property "Author" "Antmicro")
    (property "Color" "Green")
    (property "License" "Apache-2.0")
    (property "MPN" "LG L29K-G2J1-24-Z")
    (property "Manufacturer" "OSRAM")
    (property "Sheetfile" "d1600e-psu-breakout-board.kicad_sch")
    (property "Sheetname" "")
    (property "ki_description" "LED, Green, SMD, 0603, 20 mA, 1.7 V, 570 nm")
    (property "ki_keywords" "SMT, DIODE, SEMICONDUCTOR, LED")
    (zone_connect 1)
    (attr smd)
    (fp_text reference "D4" (at -0.8 1.65) (layer "F.SilkS")
        (effects (font (size 0.7 0.7) (thickness 0.15)) (justify left bottom))
    )
    (fp_text value "LED_G_0603_LG_L29K-G2J1-24-Z" (at -0.001 1.599) (layer "F.Fab")
        (effects (font (size 0.7 0.7) (thickness 0.15)) (justify left bottom))
    )
    (fp_text user "License: Apache-2.0" (at -1.4224 3.599) (layer "F.Fab") hide
        (effects (font (size 0.7 0.7) (thickness 0.15)) (justify left bottom))
    )
    (fp_text user "${REFERENCE}" (at -1.4224 5.999) (layer "F.Fab") hide
        (effects (font (size 0.7 0.7) (thickness 0.15)) (justify left bottom))
    )
    (fp_text user "Author: Antmicro" (at -1.4224 4.799) (layer "F.Fab") hide
        (effects (font (size 0.7 0.7) (thickness 0.15)) (justify left bottom))
    )
    (fp_line (start -1.18 -0.319) (end -1.18 0.321)
      (stroke (width 0.15) (type solid)) (layer "F.SilkS"))
    (fp_line (start -0.094672 0.001008) (end -0.24 0.001008)
      (stroke (width 0.1) (type solid)) (layer "F.SilkS"))
    (fp_line (start -0.094672 0.001008) (end 0.105328 -0.198992)
      (stroke (width 0.1) (type solid)) (layer "F.SilkS"))
    (fp_line (start -0.094672 0.201008) (end -0.094672 -0.198992)
      (stroke (width 0.1) (type solid)) (layer "F.SilkS"))
    (fp_line (start 0.105328 0.001008) (end 0.24 0.001)
      (stroke (width 0.1) (type solid)) (layer "F.SilkS"))
    (fp_line (start 0.105328 0.201008) (end -0.094672 0.001008)
      (stroke (width 0.1) (type solid)) (layer "F.SilkS"))
    (fp_line (start 0.105328 0.201008) (end 0.105328 -0.198992)
      (stroke (width 0.1) (type solid)) (layer "F.SilkS"))
    (fp_line (start 0.22 -0.35) (end -0.22 -0.35)
      (stroke (width 0.15) (type solid)) (layer "F.SilkS"))
    (fp_line (start 0.22 0.35) (end -0.22 0.35)
      (stroke (width 0.15) (type solid)) (layer "F.SilkS"))
    (fp_rect (start 1.25 0.65) (end -1.25 -0.65)
      (stroke (width 0.05) (type solid)) (fill none) (layer "F.CrtYd"))
    (fp_line (start -0.199 -0.202) (end -0.199 0.1)
      (stroke (width 0.15) (type solid)) (layer "F.Fab"))
    (fp_line (start -0.199 0) (end -0.597 0)
      (stroke (width 0.15) (type solid)) (layer "F.Fab"))
    (fp_line (start -0.199 0.2) (end -0.199 0.1)
      (stroke (width 0.15) (type solid)) (layer "F.Fab"))
    (fp_line (start -0.101 0) (end 0.201 0.2)
      (stroke (width 0.15) (type solid)) (layer "F.Fab"))
    (fp_line (start 0.201 -0.202) (end -0.101 0)
      (stroke (width 0.15) (type solid)) (layer "F.Fab"))
    (fp_line (start 0.201 0) (end 0.201 -0.202)
      (stroke (width 0.15) (type solid)) (layer "F.Fab"))
    (fp_line (start 0.201 0.2) (end 0.201 0)
      (stroke (width 0.15) (type solid)) (layer "F.Fab"))
    (fp_line (start 0.599 0) (end 0.201 0)
      (stroke (width 0.15) (type solid)) (layer "F.Fab"))
    (fp_rect (start 0.848 0.4) (end -0.85 -0.402)
      (stroke (width 0.15) (type solid)) (fill none) (layer "F.Fab"))
    (pad "1" smd roundrect (at -0.7 0 180) (size 0.8 1) (layers "F.Cu" "F.Paste" "F.Mask") (roundrect_rratio 0.2)
      (net 4 "GND") (pinfunction "C") (pintype "passive"))
    (pad "2" smd roundrect (at 0.7 0 180) (size 0.8 1) (layers "F.Cu" "F.Paste" "F.Mask") (roundrect_rratio 0.2)
      (net 37 "Net-(D4-A)") (pinfunction "A") (pintype "passive"))
  )
	(footprint "antmicro-footprints:R_0402_1005Metric" (layer "F.Cu")
    (at 111.55 89.4 180)
    (descr "Resistor SMD 0402")
    (tags "resistor SMD 0402")
    (property "Author" "Antmicro")
    (property "DNP" "DNP")
    (property "License" "Apache-2.0")
    (property "MPN" "CR0402-FX-1002GLF")
    (property "Manufacturer" "Bourns")
    (property "Sheetfile" "power-switch.kicad_sch")
    (property "Sheetname" "Power switch 1")
    (property "Tolerance" "1%")
    (property "Val" "10k")
    (property "dnp" "")
    (property "exclude_from_bom" "")
    (property "ki_description" "SMD Chip Resistor, 10 kohm, ± 1%, 62.5 mW, 0402 [1005 Metric], Thick Film, General Purpose")
    (property "ki_keywords" "0402, SMT, RESISTOR, PASSIVE")
    (attr smd exclude_from_bom)
    (fp_text reference "R46" (at 1.85 -1.4 180) (layer "F.SilkS")
        (effects (font (size 0.7 0.7) (thickness 0.15)) (justify left bottom))
    )
    (fp_text value "R_10k_0402" (at -1.011843 1.772047 180) (layer "F.Fab")
        (effects (font (size 0.7 0.7) (thickness 0.15)) (justify left bottom))
    )
    (fp_text user "${REFERENCE}" (at -0.95 3.168 180) (layer "F.Fab") hide
        (effects (font (size 0.7 0.7) (thickness 0.15)) (justify left bottom))
    )
    (fp_text user "Author: Antmicro" (at -0.95 4.169 180) (layer "F.Fab") hide
        (effects (font (size 0.7 0.7) (thickness 0.15)) (justify left bottom))
    )
    (fp_text user "License: Apache-2.0" (at -0.95 5.169 180) (layer "F.Fab") hide
        (effects (font (size 0.7 0.7) (thickness 0.15)) (justify left bottom))
    )
    (fp_rect (start -0.925 -0.47) (end 0.925 0.47)
      (stroke (width 0.05) (type default)) (fill none) (layer "F.CrtYd"))
    (fp_rect (start -0.5 -0.25) (end 0.5 0.25)
      (stroke (width 0.15) (type solid)) (fill none) (layer "F.Fab"))
    (pad "1" smd roundrect (at -0.48 0 180) (size 0.59 0.64) (layers "F.Cu" "F.Paste" "F.Mask") (roundrect_rratio 0.25)
      (net 23 "/Power Cycling & Current Measurement/PC_1") (pintype "passive"))
    (pad "2" smd roundrect (at 0.48 0 180) (size 0.59 0.64) (layers "F.Cu" "F.Paste" "F.Mask") (roundrect_rratio 0.25)
      (net 4 "GND") (pintype "passive"))
  )
)
